(kicad_pcb
	(version 20260206)
	(generator "pcbnew")
	(generator_version "10.0")
	(general
		(thickness 1.6)
		(legacy_teardrops no)
	)
	(paper "A4")
	(title_block
		(title "04192023_DAF0TMB3IC0_F0TG_MB_C_brd_V02_OCP.brd")
		(comment 1 "Grand Teton / footprints 5685-5691 of 8354")
	)
	(layers
		(0 "F.Cu" signal "TOP")
		(4 "In1.Cu" signal "GND")
		(6 "In2.Cu" signal "IN1")
		(8 "In3.Cu" signal "GND1")
		(10 "In4.Cu" signal "IN2")
		(12 "In5.Cu" signal "GND2")
		(14 "In6.Cu" signal "IN3")
		(16 "In7.Cu" signal "GND3")
		(18 "In8.Cu" signal "VCC")
		(20 "In9.Cu" signal "VCC1")
		(22 "In10.Cu" signal "GND4")
		(24 "In11.Cu" signal "IN4")
		(26 "In12.Cu" signal "GND5")
		(28 "In13.Cu" signal "IN5")
		(30 "In14.Cu" signal "GND6")
		(32 "In15.Cu" signal "IN6")
		(34 "In16.Cu" signal "GND7")
		(2 "B.Cu" signal "BOTTOM")
		(9 "F.Adhes" user "F.Adhesive")
		(11 "B.Adhes" user "B.Adhesive")
		(13 "F.Paste" user "Package Geometry/Pastemask Top")
		(15 "B.Paste" user "Package Geometry/Pastemask Bottom")
		(5 "F.SilkS" user "Ref Des/Silkscreen Top")
		(7 "B.SilkS" user "Ref Des/Silkscreen Bottom")
		(1 "F.Mask" user "Board Geometry/Soldermask Top")
		(3 "B.Mask" user "Board Geometry/Soldermask Bottom")
		(17 "Dwgs.User" user "User.Drawings")
		(19 "Cmts.User" user "User.Comments")
		(21 "Eco1.User" user "User.Eco1")
		(23 "Eco2.User" user "User.Eco2")
		(25 "Edge.Cuts" user "Board Geometry/Outline")
		(27 "Margin" user)
		(31 "F.CrtYd" user "Package Geometry/Place Bound Top")
		(29 "B.CrtYd" user "Package Geometry/Place Bound Bottom")
		(35 "F.Fab" user "Ref Des/Assembly Top")
		(33 "B.Fab" user "Ref Des/Assembly Bottom")
	)
	(footprint ""
		(layer "B.Cu")
		(at 323.386958 -203.917296 -90)
		(property "Reference" "R396"
			(at 0 0 90)
			(layer "B.SilkS")
			(hide yes)
			(effects
				(font
					(size 1.27 1.27)
				)
				(justify mirror)
			)
		)
		(property "Value" ""
			(at 0 0 90)
			(layer "B.Fab")
			(effects
				(font
					(size 1.27 1.27)
				)
				(justify mirror)
			)
		)
		(duplicate_pad_numbers_are_jumpers no)
		(fp_line
			(start -0.7874 0.4064)
			(end 0.7874 0.4064)
			(stroke
				(width 0.1524)
				(type default)
			)
			(layer "B.SilkS")
		)
		(fp_line
			(start 0.7874 0.4064)
			(end 0.7874 -0.4064)
			(stroke
				(width 0.1524)
				(type default)
			)
			(layer "B.SilkS")
		)
		(fp_line
			(start -0.7874 -0.4064)
			(end -0.7874 0.4064)
			(stroke
				(width 0.1524)
				(type default)
			)
			(layer "B.SilkS")
		)
		(fp_line
			(start 0.7874 -0.4064)
			(end -0.7874 -0.4064)
			(stroke
				(width 0.1524)
				(type default)
			)
			(layer "B.SilkS")
		)
		(fp_line
			(start -0.67945 0.3048)
			(end -0.120396 0.3048)
			(stroke
				(width 0.1)
				(type default)
			)
			(layer "B.Fab")
		)
		(fp_line
			(start -0.120396 0.3048)
			(end -0.120396 0.2794)
			(stroke
				(width 0.1)
				(type default)
			)
			(layer "B.Fab")
		)
		(fp_line
			(start 0.12065 0.3048)
			(end 0.67945 0.3048)
			(stroke
				(width 0.1)
				(type default)
			)
			(layer "B.Fab")
		)
		(fp_line
			(start 0.67945 0.3048)
			(end 0.67945 -0.305054)
			(stroke
				(width 0.1)
				(type default)
			)
			(layer "B.Fab")
		)
		(fp_line
			(start -0.120396 0.2794)
			(end 0.12065 0.2794)
			(stroke
				(width 0.1)
				(type default)
			)
			(layer "B.Fab")
		)
		(fp_line
			(start 0.12065 0.2794)
			(end 0.12065 0.3048)
			(stroke
				(width 0.1)
				(type default)
			)
			(layer "B.Fab")
		)
		(fp_line
			(start -0.12065 -0.2794)
			(end -0.12065 -0.3048)
			(stroke
				(width 0.1)
				(type default)
			)
			(layer "B.Fab")
		)
		(fp_line
			(start 0.12065 -0.2794)
			(end -0.12065 -0.2794)
			(stroke
				(width 0.1)
				(type default)
			)
			(layer "B.Fab")
		)
		(fp_line
			(start -0.67945 -0.3048)
			(end -0.67945 0.3048)
			(stroke
				(width 0.1)
				(type default)
			)
			(layer "B.Fab")
		)
		(fp_line
			(start -0.12065 -0.3048)
			(end -0.67945 -0.3048)
			(stroke
				(width 0.1)
				(type default)
			)
			(layer "B.Fab")
		)
		(fp_line
			(start 0.12065 -0.305054)
			(end 0.12065 -0.2794)
			(stroke
				(width 0.1)
				(type default)
			)
			(layer "B.Fab")
		)
		(fp_line
			(start 0.67945 -0.305054)
			(end 0.12065 -0.305054)
			(stroke
				(width 0.1)
				(type default)
			)
			(layer "B.Fab")
		)
		(pad "1" smd circle
			(at 0.40005 0 90)
			(size 0 0)
			(layers "B.Cu" "B.Mask" "B.Paste")
			(net "P3V3_AUX")
		)
		(pad "2" smd circle
			(at -0.40005 0 90)
			(size 0 0)
			(layers "B.Cu" "B.Mask" "B.Paste")
			(net "CPU0_SP5R2")
		)
	)
	(footprint ""
		(layer "B.Cu")
		(at 12.234418 -414.37687 90)
		(property "Reference" "PR6808"
			(at 0 0 90)
			(layer "B.SilkS")
			(hide yes)
			(effects
				(font
					(size 1.27 1.27)
				)
				(justify mirror)
			)
		)
		(property "Value" ""
			(at 0 0 90)
			(layer "B.Fab")
			(effects
				(font
					(size 1.27 1.27)
				)
				(justify mirror)
			)
		)
		(duplicate_pad_numbers_are_jumpers no)
		(fp_line
			(start 0.7874 -0.4064)
			(end -0.7874 -0.4064)
			(stroke
				(width 0.1524)
				(type default)
			)
			(layer "B.SilkS")
		)
		(fp_line
			(start -0.7874 -0.4064)
			(end -0.7874 0.4064)
			(stroke
				(width 0.1524)
				(type default)
			)
			(layer "B.SilkS")
		)
		(fp_line
			(start 0.7874 0.4064)
			(end 0.7874 -0.4064)
			(stroke
				(width 0.1524)
				(type default)
			)
			(layer "B.SilkS")
		)
		(fp_line
			(start -0.7874 0.4064)
			(end 0.7874 0.4064)
			(stroke
				(width 0.1524)
				(type default)
			)
			(layer "B.SilkS")
		)
		(fp_line
			(start 0.67945 -0.305054)
			(end 0.12065 -0.305054)
			(stroke
				(width 0.1)
				(type default)
			)
			(layer "B.Fab")
		)
		(fp_line
			(start 0.12065 -0.305054)
			(end 0.12065 -0.2794)
			(stroke
				(width 0.1)
				(type default)
			)
			(layer "B.Fab")
		)
		(fp_line
			(start -0.12065 -0.3048)
			(end -0.67945 -0.3048)
			(stroke
				(width 0.1)
				(type default)
			)
			(layer "B.Fab")
		)
		(fp_line
			(start -0.67945 -0.3048)
			(end -0.67945 0.3048)
			(stroke
				(width 0.1)
				(type default)
			)
			(layer "B.Fab")
		)
		(fp_line
			(start 0.12065 -0.2794)
			(end -0.12065 -0.2794)
			(stroke
				(width 0.1)
				(type default)
			)
			(layer "B.Fab")
		)
		(fp_line
			(start -0.12065 -0.2794)
			(end -0.12065 -0.3048)
			(stroke
				(width 0.1)
				(type default)
			)
			(layer "B.Fab")
		)
		(fp_line
			(start 0.12065 0.2794)
			(end 0.12065 0.3048)
			(stroke
				(width 0.1)
				(type default)
			)
			(layer "B.Fab")
		)
		(fp_line
			(start -0.120396 0.2794)
			(end 0.12065 0.2794)
			(stroke
				(width 0.1)
				(type default)
			)
			(layer "B.Fab")
		)
		(fp_line
			(start 0.67945 0.3048)
			(end 0.67945 -0.305054)
			(stroke
				(width 0.1)
				(type default)
			)
			(layer "B.Fab")
		)
		(fp_line
			(start 0.12065 0.3048)
			(end 0.67945 0.3048)
			(stroke
				(width 0.1)
				(type default)
			)
			(layer "B.Fab")
		)
		(fp_line
			(start -0.120396 0.3048)
			(end -0.120396 0.2794)
			(stroke
				(width 0.1)
				(type default)
			)
			(layer "B.Fab")
		)
		(fp_line
			(start -0.67945 0.3048)
			(end -0.120396 0.3048)
			(stroke
				(width 0.1)
				(type default)
			)
			(layer "B.Fab")
		)
		(pad "1" smd circle
			(at 0.40005 0 270)
			(size 0 0)
			(layers "B.Cu" "B.Mask" "B.Paste")
			(net "P12V_AUX")
		)
		(pad "2" smd circle
			(at -0.40005 0 270)
			(size 0 0)
			(layers "B.Cu" "B.Mask" "B.Paste")
			(net "P0V9_RETIMER_CPU1_VMON")
		)
	)
	(footprint ""
		(layer "B.Cu")
		(at 131.27863 -386.766562 90)
		(property "Reference" "C470"
			(at 0 0 90)
			(layer "B.SilkS")
			(hide yes)
			(effects
				(font
					(size 1.27 1.27)
				)
				(justify mirror)
			)
		)
		(property "Value" ""
			(at 0 0 90)
			(layer "B.Fab")
			(effects
				(font
					(size 1.27 1.27)
				)
				(justify mirror)
			)
		)
		(duplicate_pad_numbers_are_jumpers no)
		(fp_line
			(start 0.299974 -0.150114)
			(end -0.299974 -0.150114)
			(stroke
				(width 0.1)
				(type default)
			)
			(layer "B.Fab")
		)
		(fp_line
			(start -0.299974 -0.150114)
			(end -0.299974 0.150114)
			(stroke
				(width 0.1)
				(type default)
			)
			(layer "B.Fab")
		)
		(fp_line
			(start 0.299974 0.150114)
			(end 0.299974 -0.150114)
			(stroke
				(width 0.1)
				(type default)
			)
			(layer "B.Fab")
		)
		(fp_line
			(start -0.299974 0.150114)
			(end 0.299974 0.150114)
			(stroke
				(width 0.1)
				(type default)
			)
			(layer "B.Fab")
		)
		(pad "1" smd rect
			(at 0.2667 0 270)
			(size 0.3048 0.381)
			(layers "B.Cu" "B.Mask" "B.Paste")
			(net "P0V9_CPU1_RT3_2A")
		)
		(pad "2" smd rect
			(at -0.2667 0 270)
			(size 0.3048 0.381)
			(layers "B.Cu" "B.Mask" "B.Paste")
			(net "GND")
		)
	)
	(footprint ""
		(layer "B.Cu")
		(at 92.992702 -181.616604 90)
		(property "Reference" "PR186"
			(at 0 0 90)
			(layer "B.SilkS")
			(hide yes)
			(effects
				(font
					(size 1.27 1.27)
				)
				(justify mirror)
			)
		)
		(property "Value" ""
			(at 0 0 90)
			(layer "B.Fab")
			(effects
				(font
					(size 1.27 1.27)
				)
				(justify mirror)
			)
		)
		(duplicate_pad_numbers_are_jumpers no)
		(fp_line
			(start 0.7874 -0.4064)
			(end -0.7874 -0.4064)
			(stroke
				(width 0.1524)
				(type default)
			)
			(layer "B.SilkS")
		)
		(fp_line
			(start -0.7874 -0.4064)
			(end -0.7874 0.4064)
			(stroke
				(width 0.1524)
				(type default)
			)
			(layer "B.SilkS")
		)
		(fp_line
			(start 0.7874 0.4064)
			(end 0.7874 -0.4064)
			(stroke
				(width 0.1524)
				(type default)
			)
			(layer "B.SilkS")
		)
		(fp_line
			(start -0.7874 0.4064)
			(end 0.7874 0.4064)
			(stroke
				(width 0.1524)
				(type default)
			)
			(layer "B.SilkS")
		)
		(fp_line
			(start 0.67945 -0.305054)
			(end 0.12065 -0.305054)
			(stroke
				(width 0.1)
				(type default)
			)
			(layer "B.Fab")
		)
		(fp_line
			(start 0.12065 -0.305054)
			(end 0.12065 -0.2794)
			(stroke
				(width 0.1)
				(type default)
			)
			(layer "B.Fab")
		)
		(fp_line
			(start -0.12065 -0.3048)
			(end -0.67945 -0.3048)
			(stroke
				(width 0.1)
				(type default)
			)
			(layer "B.Fab")
		)
		(fp_line
			(start -0.67945 -0.3048)
			(end -0.67945 0.3048)
			(stroke
				(width 0.1)
				(type default)
			)
			(layer "B.Fab")
		)
		(fp_line
			(start 0.12065 -0.2794)
			(end -0.12065 -0.2794)
			(stroke
				(width 0.1)
				(type default)
			)
			(layer "B.Fab")
		)
		(fp_line
			(start -0.12065 -0.2794)
			(end -0.12065 -0.3048)
			(stroke
				(width 0.1)
				(type default)
			)
			(layer "B.Fab")
		)
		(fp_line
			(start 0.12065 0.2794)
			(end 0.12065 0.3048)
			(stroke
				(width 0.1)
				(type default)
			)
			(layer "B.Fab")
		)
		(fp_line
			(start -0.120396 0.2794)
			(end 0.12065 0.2794)
			(stroke
				(width 0.1)
				(type default)
			)
			(layer "B.Fab")
		)
		(fp_line
			(start 0.67945 0.3048)
			(end 0.67945 -0.305054)
			(stroke
				(width 0.1)
				(type default)
			)
			(layer "B.Fab")
		)
		(fp_line
			(start 0.12065 0.3048)
			(end 0.67945 0.3048)
			(stroke
				(width 0.1)
				(type default)
			)
			(layer "B.Fab")
		)
		(fp_line
			(start -0.120396 0.3048)
			(end -0.120396 0.2794)
			(stroke
				(width 0.1)
				(type default)
			)
			(layer "B.Fab")
		)
		(fp_line
			(start -0.67945 0.3048)
			(end -0.120396 0.3048)
			(stroke
				(width 0.1)
				(type default)
			)
			(layer "B.Fab")
		)
		(pad "1" smd circle
			(at 0.40005 0 270)
			(size 0 0)
			(layers "B.Cu" "B.Mask" "B.Paste")
			(net "PVDDCR_CPU0_P1_PVCC")
		)
		(pad "2" smd circle
			(at -0.40005 0 270)
			(size 0 0)
			(layers "B.Cu" "B.Mask" "B.Paste")
			(net "PVDDCR_CPU0_P1_VCC2")
		)
	)
	(footprint ""
		(layer "B.Cu")
		(at 17.999456 -383.028698 -90)
		(property "Reference" "PC6642_2"
			(at 0 0 90)
			(layer "B.SilkS")
			(hide yes)
			(effects
				(font
					(size 1.27 1.27)
				)
				(justify mirror)
			)
		)
		(property "Value" ""
			(at 0 0 90)
			(layer "B.Fab")
			(effects
				(font
					(size 1.27 1.27)
				)
				(justify mirror)
			)
		)
		(duplicate_pad_numbers_are_jumpers no)
		(fp_line
			(start -1.524 0.762)
			(end 1.524 0.762)
			(stroke
				(width 0.1524)
				(type default)
			)
			(layer "B.SilkS")
		)
		(fp_line
			(start 1.524 0.762)
			(end 1.524 -0.762)
			(stroke
				(width 0.1524)
				(type default)
			)
			(layer "B.SilkS")
		)
		(fp_line
			(start -1.524 -0.762)
			(end -1.524 0.762)
			(stroke
				(width 0.1524)
				(type default)
			)
			(layer "B.SilkS")
		)
		(fp_line
			(start 1.524 -0.762)
			(end -1.524 -0.762)
			(stroke
				(width 0.1524)
				(type default)
			)
			(layer "B.SilkS")
		)
		(fp_line
			(start -1.1049 0.724916)
			(end -1.1049 -0.724916)
			(stroke
				(width 0.1)
				(type default)
			)
			(layer "B.Fab")
		)
		(fp_line
			(start 1.1049 0.724916)
			(end -1.1049 0.724916)
			(stroke
				(width 0.1)
				(type default)
			)
			(layer "B.Fab")
		)
		(fp_line
			(start -1.1049 -0.724916)
			(end 1.1049 -0.724916)
			(stroke
				(width 0.1)
				(type default)
			)
			(layer "B.Fab")
		)
		(fp_line
			(start 1.1049 -0.724916)
			(end 1.1049 0.724916)
			(stroke
				(width 0.1)
				(type default)
			)
			(layer "B.Fab")
		)
		(pad "1" smd rect
			(at 0.889 0 270)
			(size 1.016 1.27)
			(layers "B.Cu" "B.Mask" "B.Paste")
			(net "P0V9_CPU1_RT_2D")
		)
		(pad "2" smd rect
			(at -0.889 0 270)
			(size 1.016 1.27)
			(layers "B.Cu" "B.Mask" "B.Paste")
			(net "GND")
		)
	)
	(footprint ""
		(layer "B.Cu")
		(at 229.616 -216.662 180)
		(property "Reference" "R290"
			(at 0 0 0)
			(layer "B.SilkS")
			(hide yes)
			(effects
				(font
					(size 1.27 1.27)
				)
				(justify mirror)
			)
		)
		(property "Value" ""
			(at 0 0 0)
			(layer "B.Fab")
			(effects
				(font
					(size 1.27 1.27)
				)
				(justify mirror)
			)
		)
		(duplicate_pad_numbers_are_jumpers no)
		(fp_line
			(start 0.7874 0.4064)
			(end 0.7874 -0.4064)
			(stroke
				(width 0.1524)
				(type default)
			)
			(layer "B.SilkS")
		)
		(fp_line
			(start 0.7874 -0.4064)
			(end -0.7874 -0.4064)
			(stroke
				(width 0.1524)
				(type default)
			)
			(layer "B.SilkS")
		)
		(fp_line
			(start -0.7874 0.4064)
			(end 0.7874 0.4064)
			(stroke
				(width 0.1524)
				(type default)
			)
			(layer "B.SilkS")
		)
		(fp_line
			(start -0.7874 -0.4064)
			(end -0.7874 0.4064)
			(stroke
				(width 0.1524)
				(type default)
			)
			(layer "B.SilkS")
		)
		(fp_line
			(start 0.67945 0.3048)
			(end 0.67945 -0.305054)
			(stroke
				(width 0.1)
				(type default)
			)
			(layer "B.Fab")
		)
		(fp_line
			(start 0.67945 -0.305054)
			(end 0.12065 -0.305054)
			(stroke
				(width 0.1)
				(type default)
			)
			(layer "B.Fab")
		)
		(fp_line
			(start 0.12065 0.3048)
			(end 0.67945 0.3048)
			(stroke
				(width 0.1)
				(type default)
			)
			(layer "B.Fab")
		)
		(fp_line
			(start 0.12065 0.2794)
			(end 0.12065 0.3048)
			(stroke
				(width 0.1)
				(type default)
			)
			(layer "B.Fab")
		)
		(fp_line
			(start 0.12065 -0.2794)
			(end -0.12065 -0.2794)
			(stroke
				(width 0.1)
				(type default)
			)
			(layer "B.Fab")
		)
		(fp_line
			(start 0.12065 -0.305054)
			(end 0.12065 -0.2794)
			(stroke
				(width 0.1)
				(type default)
			)
			(layer "B.Fab")
		)
		(fp_line
			(start -0.120396 0.3048)
			(end -0.120396 0.2794)
			(stroke
				(width 0.1)
				(type default)
			)
			(layer "B.Fab")
		)
		(fp_line
			(start -0.120396 0.2794)
			(end 0.12065 0.2794)
			(stroke
				(width 0.1)
				(type default)
			)
			(layer "B.Fab")
		)
		(fp_line
			(start -0.12065 -0.2794)
			(end -0.12065 -0.3048)
			(stroke
				(width 0.1)
				(type default)
			)
			(layer "B.Fab")
		)
		(fp_line
			(start -0.12065 -0.3048)
			(end -0.67945 -0.3048)
			(stroke
				(width 0.1)
				(type default)
			)
			(layer "B.Fab")
		)
		(fp_line
			(start -0.67945 0.3048)
			(end -0.120396 0.3048)
			(stroke
				(width 0.1)
				(type default)
			)
			(layer "B.Fab")
		)
		(fp_line
			(start -0.67945 -0.3048)
			(end -0.67945 0.3048)
			(stroke
				(width 0.1)
				(type default)
			)
			(layer "B.Fab")
		)
		(pad "1" smd circle
			(at 0.40005 0)
			(size 0 0)
			(layers "B.Cu" "B.Mask" "B.Paste")
			(net "PVDD11_S3_P0")
		)
		(pad "2" smd circle
			(at -0.40005 0)
			(size 0 0)
			(layers "B.Cu" "B.Mask" "B.Paste")
			(net "SMB_CPU0_CPU1_APML_BUF2_SDA_R2")
		)
	)
	(footprint ""
		(layer "B.Cu")
		(at 137.928604 -64.036702 -90)
		(property "Reference" "R6090"
			(at 0 0 90)
			(layer "B.SilkS")
			(hide yes)
			(effects
				(font
					(size 1.27 1.27)
				)
				(justify mirror)
			)
		)
		(property "Value" ""
			(at 0 0 90)
			(layer "B.Fab")
			(effects
				(font
					(size 1.27 1.27)
				)
				(justify mirror)
			)
		)
		(duplicate_pad_numbers_are_jumpers no)
		(fp_line
			(start -0.7874 0.4064)
			(end 0.7874 0.4064)
			(stroke
				(width 0.1524)
				(type default)
			)
			(layer "B.SilkS")
		)
		(fp_line
			(start 0.7874 0.4064)
			(end 0.7874 -0.4064)
			(stroke
				(width 0.1524)
				(type default)
			)
			(layer "B.SilkS")
		)
		(fp_line
			(start -0.7874 -0.4064)
			(end -0.7874 0.4064)
			(stroke
				(width 0.1524)
				(type default)
			)
			(layer "B.SilkS")
		)
		(fp_line
			(start 0.7874 -0.4064)
			(end -0.7874 -0.4064)
			(stroke
				(width 0.1524)
				(type default)
			)
			(layer "B.SilkS")
		)
		(fp_line
			(start -0.67945 0.3048)
			(end -0.120396 0.3048)
			(stroke
				(width 0.1)
				(type default)
			)
			(layer "B.Fab")
		)
		(fp_line
			(start -0.120396 0.3048)
			(end -0.120396 0.2794)
			(stroke
				(width 0.1)
				(type default)
			)
			(layer "B.Fab")
		)
		(fp_line
			(start 0.12065 0.3048)
			(end 0.67945 0.3048)
			(stroke
				(width 0.1)
				(type default)
			)
			(layer "B.Fab")
		)
		(fp_line
			(start 0.67945 0.3048)
			(end 0.67945 -0.305054)
			(stroke
				(width 0.1)
				(type default)
			)
			(layer "B.Fab")
		)
		(fp_line
			(start -0.120396 0.2794)
			(end 0.12065 0.2794)
			(stroke
				(width 0.1)
				(type default)
			)
			(layer "B.Fab")
		)
		(fp_line
			(start 0.12065 0.2794)
			(end 0.12065 0.3048)
			(stroke
				(width 0.1)
				(type default)
			)
			(layer "B.Fab")
		)
		(fp_line
			(start -0.12065 -0.2794)
			(end -0.12065 -0.3048)
			(stroke
				(width 0.1)
				(type default)
			)
			(layer "B.Fab")
		)
		(fp_line
			(start 0.12065 -0.2794)
			(end -0.12065 -0.2794)
			(stroke
				(width 0.1)
				(type default)
			)
			(layer "B.Fab")
		)
		(fp_line
			(start -0.67945 -0.3048)
			(end -0.67945 0.3048)
			(stroke
				(width 0.1)
				(type default)
			)
			(layer "B.Fab")
		)
		(fp_line
			(start -0.12065 -0.3048)
			(end -0.67945 -0.3048)
			(stroke
				(width 0.1)
				(type default)
			)
			(layer "B.Fab")
		)
		(fp_line
			(start 0.12065 -0.305054)
			(end 0.12065 -0.2794)
			(stroke
				(width 0.1)
				(type default)
			)
			(layer "B.Fab")
		)
		(fp_line
			(start 0.67945 -0.305054)
			(end 0.12065 -0.305054)
			(stroke
				(width 0.1)
				(type default)
			)
			(layer "B.Fab")
		)
		(pad "1" smd circle
			(at 0.40005 0 90)
			(size 0 0)
			(layers "B.Cu" "B.Mask" "B.Paste")
			(net "JTAG_SCM_PLD_TCK")
		)
		(pad "2" smd circle
			(at -0.40005 0 90)
			(size 0 0)
			(layers "B.Cu" "B.Mask" "B.Paste")
			(net "GND")
		)
	)
)
